# T6G (Grand Teton) — schematic netlist excerpt (pin names and nets, part order shuffled) for the footprints in the layout excerpt that follows; sources: Cadence DE-HDL packaged netlist, KiCad conversion of 04192023_DAF0TMB3IC0_F0TG_MB_C_brd_V02_OCP.brd

R22  Q_RES  100 1% CHIP  pkg 0402LF  page 167 : A = P1V8_AUX ; B = PU_BIOS_USB_RECOVERY
PC6540  Q_CAP  3300PF 50V 10% X7R  pkg 0402  page 362 : A = P0V9_RETIMER_CPU0_SENSE_R_P ; B = P0V9_RETIMER_CPU0_SENSE_SH_N

(kicad_pcb
	(version 20260206)
	(generator "pcbnew")
	(generator_version "10.0")
	(general
		(thickness 1.6)
		(legacy_teardrops no)
	)
	(paper "A4")
	(title_block
		(title "04192023_DAF0TMB3IC0_F0TG_MB_C_brd_V02_OCP.brd")
		(comment 1 "Grand Teton / footprints 2059-2060 of 8354")
	)
	(layers
		(0 "F.Cu" signal "TOP")
		(4 "In1.Cu" signal "GND")
		(6 "In2.Cu" signal "IN1")
		(8 "In3.Cu" signal "GND1")
		(10 "In4.Cu" signal "IN2")
		(12 "In5.Cu" signal "GND2")
		(14 "In6.Cu" signal "IN3")
		(16 "In7.Cu" signal "GND3")
		(18 "In8.Cu" signal "VCC")
		(20 "In9.Cu" signal "VCC1")
		(22 "In10.Cu" signal "GND4")
		(24 "In11.Cu" signal "IN4")
		(26 "In12.Cu" signal "GND5")
		(28 "In13.Cu" signal "IN5")
		(30 "In14.Cu" signal "GND6")
		(32 "In15.Cu" signal "IN6")
		(34 "In16.Cu" signal "GND7")
		(2 "B.Cu" signal "BOTTOM")
		(9 "F.Adhes" user "F.Adhesive")
		(11 "B.Adhes" user "B.Adhesive")
		(13 "F.Paste" user "Package Geometry/Pastemask Top")
		(15 "B.Paste" user "Package Geometry/Pastemask Bottom")
		(5 "F.SilkS" user "Ref Des/Silkscreen Top")
		(7 "B.SilkS" user "Ref Des/Silkscreen Bottom")
		(1 "F.Mask" user "Board Geometry/Soldermask Top")
		(3 "B.Mask" user "Board Geometry/Soldermask Bottom")
		(17 "Dwgs.User" user "User.Drawings")
		(19 "Cmts.User" user "User.Comments")
		(21 "Eco1.User" user "User.Eco1")
		(23 "Eco2.User" user "User.Eco2")
		(25 "Edge.Cuts" user "Board Geometry/Outline")
		(27 "Margin" user)
		(31 "F.CrtYd" user "Package Geometry/Place Bound Top")
		(29 "B.CrtYd" user "Package Geometry/Place Bound Bottom")
		(35 "F.Fab" user "Ref Des/Assembly Top")
		(33 "B.Fab" user "Ref Des/Assembly Bottom")
	)
	(footprint ""
		(layer "F.Cu")
		(at 442.077602 -420.10711)
		(property "Reference" "PC6540"
			(at 0 0 0)
			(layer "F.SilkS")
			(hide yes)
			(effects
				(font
					(size 1.27 1.27)
				)
			)
		)
		(property "Value" ""
			(at 0 0 0)
			(layer "F.Fab")
			(effects
				(font
					(size 1.27 1.27)
				)
			)
		)
		(duplicate_pad_numbers_are_jumpers no)
		(fp_line
			(start -0.7874 -0.4064)
			(end 0.7874 -0.4064)
			(stroke
				(width 0.1524)
				(type default)
			)
			(layer "F.SilkS")
		)
		(fp_line
			(start -0.7874 0.4064)
			(end -0.7874 -0.4064)
			(stroke
				(width 0.1524)
				(type default)
			)
			(layer "F.SilkS")
		)
		(fp_line
			(start 0.7874 -0.4064)
			(end 0.7874 0.4064)
			(stroke
				(width 0.1524)
				(type default)
			)
			(layer "F.SilkS")
		)
		(fp_line
			(start 0.7874 0.4064)
			(end -0.7874 0.4064)
			(stroke
				(width 0.1524)
				(type default)
			)
			(layer "F.SilkS")
		)
		(fp_line
			(start -0.67945 -0.305054)
			(end -0.12065 -0.305054)
			(stroke
				(width 0.1)
				(type default)
			)
			(layer "F.Fab")
		)
		(fp_line
			(start -0.67945 0.3048)
			(end -0.67945 -0.305054)
			(stroke
				(width 0.1)
				(type default)
			)
			(layer "F.Fab")
		)
		(fp_line
			(start -0.12065 -0.305054)
			(end -0.12065 -0.2794)
			(stroke
				(width 0.1)
				(type default)
			)
			(layer "F.Fab")
		)
		(fp_line
			(start -0.12065 -0.2794)
			(end 0.12065 -0.2794)
			(stroke
				(width 0.1)
				(type default)
			)
			(layer "F.Fab")
		)
		(fp_line
			(start -0.12065 0.2794)
			(end -0.12065 0.3048)
			(stroke
				(width 0.1)
				(type default)
			)
			(layer "F.Fab")
		)
		(fp_line
			(start -0.12065 0.3048)
			(end -0.67945 0.3048)
			(stroke
				(width 0.1)
				(type default)
			)
			(layer "F.Fab")
		)
		(fp_line
			(start 0.120396 0.2794)
			(end -0.12065 0.2794)
			(stroke
				(width 0.1)
				(type default)
			)
			(layer "F.Fab")
		)
		(fp_line
			(start 0.120396 0.3048)
			(end 0.120396 0.2794)
			(stroke
				(width 0.1)
				(type default)
			)
			(layer "F.Fab")
		)
		(fp_line
			(start 0.12065 -0.3048)
			(end 0.67945 -0.3048)
			(stroke
				(width 0.1)
				(type default)
			)
			(layer "F.Fab")
		)
		(fp_line
			(start 0.12065 -0.2794)
			(end 0.12065 -0.3048)
			(stroke
				(width 0.1)
				(type default)
			)
			(layer "F.Fab")
		)
		(fp_line
			(start 0.67945 -0.3048)
			(end 0.67945 0.3048)
			(stroke
				(width 0.1)
				(type default)
			)
			(layer "F.Fab")
		)
		(fp_line
			(start 0.67945 0.3048)
			(end 0.120396 0.3048)
			(stroke
				(width 0.1)
				(type default)
			)
			(layer "F.Fab")
		)
		(pad "1" smd circle
			(at -0.40005 0)
			(size 0 0)
			(layers "F.Cu" "F.Mask" "F.Paste")
			(net "P0V9_RETIMER_CPU0_SENSE_R_P")
		)
		(pad "2" smd circle
			(at 0.40005 0)
			(size 0 0)
			(layers "F.Cu" "F.Mask" "F.Paste")
			(net "P0V9_RETIMER_CPU0_SENSE_SH_N")
		)
	)
	(footprint ""
		(layer "F.Cu")
		(at 420.75735 -38.547548)
		(property "Reference" "R22"
			(at 0 0 0)
			(layer "F.SilkS")
			(hide yes)
			(effects
				(font
					(size 1.27 1.27)
				)
			)
		)
		(property "Value" ""
			(at 0 0 0)
			(layer "F.Fab")
			(effects
				(font
					(size 1.27 1.27)
				)
			)
		)
		(duplicate_pad_numbers_are_jumpers no)
		(fp_line
			(start -0.7874 -0.4064)
			(end 0.7874 -0.4064)
			(stroke
				(width 0.1524)
				(type default)
			)
			(layer "F.SilkS")
		)
		(fp_line
			(start -0.7874 0.4064)
			(end -0.7874 -0.4064)
			(stroke
				(width 0.1524)
				(type default)
			)
			(layer "F.SilkS")
		)
		(fp_line
			(start 0.7874 -0.4064)
			(end 0.7874 0.4064)
			(stroke
				(width 0.1524)
				(type default)
			)
			(layer "F.SilkS")
		)
		(fp_line
			(start 0.7874 0.4064)
			(end -0.7874 0.4064)
			(stroke
				(width 0.1524)
				(type default)
			)
			(layer "F.SilkS")
		)
		(fp_line
			(start -0.67945 -0.305054)
			(end -0.12065 -0.305054)
			(stroke
				(width 0.1)
				(type default)
			)
			(layer "F.Fab")
		)
		(fp_line
			(start -0.67945 0.3048)
			(end -0.67945 -0.305054)
			(stroke
				(width 0.1)
				(type default)
			)
			(layer "F.Fab")
		)
		(fp_line
			(start -0.12065 -0.305054)
			(end -0.12065 -0.2794)
			(stroke
				(width 0.1)
				(type default)
			)
			(layer "F.Fab")
		)
		(fp_line
			(start -0.12065 -0.2794)
			(end 0.12065 -0.2794)
			(stroke
				(width 0.1)
				(type default)
			)
			(layer "F.Fab")
		)
		(fp_line
			(start -0.12065 0.2794)
			(end -0.12065 0.3048)
			(stroke
				(width 0.1)
				(type default)
			)
			(layer "F.Fab")
		)
		(fp_line
			(start -0.12065 0.3048)
			(end -0.67945 0.3048)
			(stroke
				(width 0.1)
				(type default)
			)
			(layer "F.Fab")
		)
		(fp_line
			(start 0.120396 0.2794)
			(end -0.12065 0.2794)
			(stroke
				(width 0.1)
				(type default)
			)
			(layer "F.Fab")
		)
		(fp_line
			(start 0.120396 0.3048)
			(end 0.120396 0.2794)
			(stroke
				(width 0.1)
				(type default)
			)
			(layer "F.Fab")
		)
		(fp_line
			(start 0.12065 -0.3048)
			(end 0.67945 -0.3048)
			(stroke
				(width 0.1)
				(type default)
			)
			(layer "F.Fab")
		)
		(fp_line
			(start 0.12065 -0.2794)
			(end 0.12065 -0.3048)
			(stroke
				(width 0.1)
				(type default)
			)
			(layer "F.Fab")
		)
		(fp_line
			(start 0.67945 -0.3048)
			(end 0.67945 0.3048)
			(stroke
				(width 0.1)
				(type default)
			)
			(layer "F.Fab")
		)
		(fp_line
			(start 0.67945 0.3048)
			(end 0.120396 0.3048)
			(stroke
				(width 0.1)
				(type default)
			)
			(layer "F.Fab")
		)
		(pad "1" smd circle
			(at -0.40005 0)
			(size 0 0)
			(layers "F.Cu" "F.Mask" "F.Paste")
			(net "P1V8_AUX")
		)
		(pad "2" smd circle
			(at 0.40005 0)
			(size 0 0)
			(layers "F.Cu" "F.Mask" "F.Paste")
			(net "PU_BIOS_USB_RECOVERY")
		)
	)
)
